# S9S_MB_2U (Grand Teton) — schematic netlist excerpt (pin names and nets, part order shuffled) for the footprints in the layout excerpt that follows; sources: Cadence DE-HDL packaged netlist, KiCad conversion of 03242023_DA0F0TMBIJ0_F0T_Motherboard_J_brd_V01_OCP.brd

PC2156  Q_CAP  100NF 50V 10% X7R  pkg C0402  page 157 : A = P12V_OCP_IMON_1 ; B = GND
R3716  Q_RES  0 5% CHIP  pkg 0402LF  page 233 : A = SMB_LM75_0_3V3AUX_SDA_R ; B = SMB_LM75_0_3V3AUX_SDA

(kicad_pcb
	(version 20260206)
	(generator "pcbnew")
	(generator_version "10.0")
	(general
		(thickness 1.6)
		(legacy_teardrops no)
	)
	(paper "A4")
	(title_block
		(title "03242023_DA0F0TMBIJ0_F0T_Motherboard_J_brd_V01_OCP.brd")
		(comment 1 "Grand Teton / footprints 1751-1752 of 6105")
	)
	(layers
		(0 "F.Cu" signal "TOP")
		(4 "In1.Cu" signal "GND")
		(6 "In2.Cu" signal "IN1")
		(8 "In3.Cu" signal "GND1")
		(10 "In4.Cu" signal "IN2")
		(12 "In5.Cu" signal "GND2")
		(14 "In6.Cu" signal "IN3")
		(16 "In7.Cu" signal "GND3")
		(18 "In8.Cu" signal "VCC")
		(20 "In9.Cu" signal "VCC1")
		(22 "In10.Cu" signal "GND4")
		(24 "In11.Cu" signal "IN4")
		(26 "In12.Cu" signal "GND5")
		(28 "In13.Cu" signal "IN5")
		(30 "In14.Cu" signal "GND6")
		(32 "In15.Cu" signal "IN6")
		(34 "In16.Cu" signal "GND7")
		(2 "B.Cu" signal "BOTTOM")
		(9 "F.Adhes" user "F.Adhesive")
		(11 "B.Adhes" user "B.Adhesive")
		(13 "F.Paste" user "Package Geometry/Pastemask Top")
		(15 "B.Paste" user "Package Geometry/Pastemask Bottom")
		(5 "F.SilkS" user "Ref Des/Silkscreen Top")
		(7 "B.SilkS" user "Ref Des/Silkscreen Bottom")
		(1 "F.Mask" user "Board Geometry/Soldermask Top")
		(3 "B.Mask" user "Board Geometry/Soldermask Bottom")
		(17 "Dwgs.User" user "User.Drawings")
		(19 "Cmts.User" user "User.Comments")
		(21 "Eco1.User" user "User.Eco1")
		(23 "Eco2.User" user "User.Eco2")
		(25 "Edge.Cuts" user "Board Geometry/Outline")
		(27 "Margin" user)
		(31 "F.CrtYd" user "Package Geometry/Place Bound Top")
		(29 "B.CrtYd" user "Package Geometry/Place Bound Bottom")
		(35 "F.Fab" user "Ref Des/Assembly Top")
		(33 "B.Fab" user "Ref Des/Assembly Bottom")
	)
	(footprint ""
		(layer "F.Cu")
		(at 54.242716 -111.94669 180)
		(property "Reference" "R3716"
			(at 0 0 180)
			(layer "F.SilkS")
			(hide yes)
			(effects
				(font
					(size 1.27 1.27)
				)
			)
		)
		(property "Value" ""
			(at 0 0 180)
			(layer "F.Fab")
			(effects
				(font
					(size 1.27 1.27)
				)
			)
		)
		(duplicate_pad_numbers_are_jumpers no)
		(fp_line
			(start 0.7874 0.4064)
			(end -0.7874 0.4064)
			(stroke
				(width 0.1524)
				(type default)
			)
			(layer "F.SilkS")
		)
		(fp_line
			(start 0.7874 -0.4064)
			(end 0.7874 0.4064)
			(stroke
				(width 0.1524)
				(type default)
			)
			(layer "F.SilkS")
		)
		(fp_line
			(start -0.7874 0.4064)
			(end -0.7874 -0.4064)
			(stroke
				(width 0.1524)
				(type default)
			)
			(layer "F.SilkS")
		)
		(fp_line
			(start -0.7874 -0.4064)
			(end 0.7874 -0.4064)
			(stroke
				(width 0.1524)
				(type default)
			)
			(layer "F.SilkS")
		)
		(fp_line
			(start 0.67945 0.3048)
			(end 0.120396 0.3048)
			(stroke
				(width 0.1)
				(type default)
			)
			(layer "F.Fab")
		)
		(fp_line
			(start 0.67945 -0.3048)
			(end 0.67945 0.3048)
			(stroke
				(width 0.1)
				(type default)
			)
			(layer "F.Fab")
		)
		(fp_line
			(start 0.12065 -0.2794)
			(end 0.12065 -0.3048)
			(stroke
				(width 0.1)
				(type default)
			)
			(layer "F.Fab")
		)
		(fp_line
			(start 0.12065 -0.3048)
			(end 0.67945 -0.3048)
			(stroke
				(width 0.1)
				(type default)
			)
			(layer "F.Fab")
		)
		(fp_line
			(start 0.120396 0.3048)
			(end 0.120396 0.2794)
			(stroke
				(width 0.1)
				(type default)
			)
			(layer "F.Fab")
		)
		(fp_line
			(start 0.120396 0.2794)
			(end -0.12065 0.2794)
			(stroke
				(width 0.1)
				(type default)
			)
			(layer "F.Fab")
		)
		(fp_line
			(start -0.12065 0.3048)
			(end -0.67945 0.3048)
			(stroke
				(width 0.1)
				(type default)
			)
			(layer "F.Fab")
		)
		(fp_line
			(start -0.12065 0.2794)
			(end -0.12065 0.3048)
			(stroke
				(width 0.1)
				(type default)
			)
			(layer "F.Fab")
		)
		(fp_line
			(start -0.12065 -0.2794)
			(end 0.12065 -0.2794)
			(stroke
				(width 0.1)
				(type default)
			)
			(layer "F.Fab")
		)
		(fp_line
			(start -0.12065 -0.305054)
			(end -0.12065 -0.2794)
			(stroke
				(width 0.1)
				(type default)
			)
			(layer "F.Fab")
		)
		(fp_line
			(start -0.67945 0.3048)
			(end -0.67945 -0.305054)
			(stroke
				(width 0.1)
				(type default)
			)
			(layer "F.Fab")
		)
		(fp_line
			(start -0.67945 -0.305054)
			(end -0.12065 -0.305054)
			(stroke
				(width 0.1)
				(type default)
			)
			(layer "F.Fab")
		)
		(pad "1" smd circle
			(at -0.40005 0 180)
			(size 0 0)
			(layers "F.Cu" "F.Mask" "F.Paste")
			(net "SMB_LM75_0_3V3AUX_SDA_R")
		)
		(pad "2" smd circle
			(at 0.40005 0 180)
			(size 0 0)
			(layers "F.Cu" "F.Mask" "F.Paste")
			(net "SMB_LM75_0_3V3AUX_SDA")
		)
	)
	(footprint ""
		(layer "F.Cu")
		(at 439.272172 -32.173418 90)
		(property "Reference" "PC2156"
			(at 0 0 90)
			(layer "F.SilkS")
			(hide yes)
			(effects
				(font
					(size 1.27 1.27)
				)
			)
		)
		(property "Value" ""
			(at 0 0 90)
			(layer "F.Fab")
			(effects
				(font
					(size 1.27 1.27)
				)
			)
		)
		(duplicate_pad_numbers_are_jumpers no)
		(fp_line
			(start 0.7874 -0.4064)
			(end 0.7874 0.4064)
			(stroke
				(width 0.1524)
				(type default)
			)
			(layer "F.SilkS")
		)
		(fp_line
			(start -0.7874 -0.4064)
			(end 0.7874 -0.4064)
			(stroke
				(width 0.1524)
				(type default)
			)
			(layer "F.SilkS")
		)
		(fp_line
			(start 0.7874 0.4064)
			(end -0.7874 0.4064)
			(stroke
				(width 0.1524)
				(type default)
			)
			(layer "F.SilkS")
		)
		(fp_line
			(start -0.7874 0.4064)
			(end -0.7874 -0.4064)
			(stroke
				(width 0.1524)
				(type default)
			)
			(layer "F.SilkS")
		)
		(fp_line
			(start -0.12065 -0.305054)
			(end -0.12065 -0.2794)
			(stroke
				(width 0.1)
				(type default)
			)
			(layer "F.Fab")
		)
		(fp_line
			(start -0.67945 -0.305054)
			(end -0.12065 -0.305054)
			(stroke
				(width 0.1)
				(type default)
			)
			(layer "F.Fab")
		)
		(fp_line
			(start 0.67945 -0.3048)
			(end 0.67945 0.3048)
			(stroke
				(width 0.1)
				(type default)
			)
			(layer "F.Fab")
		)
		(fp_line
			(start 0.12065 -0.3048)
			(end 0.67945 -0.3048)
			(stroke
				(width 0.1)
				(type default)
			)
			(layer "F.Fab")
		)
		(fp_line
			(start 0.12065 -0.2794)
			(end 0.12065 -0.3048)
			(stroke
				(width 0.1)
				(type default)
			)
			(layer "F.Fab")
		)
		(fp_line
			(start -0.12065 -0.2794)
			(end 0.12065 -0.2794)
			(stroke
				(width 0.1)
				(type default)
			)
			(layer "F.Fab")
		)
		(fp_line
			(start 0.120396 0.2794)
			(end -0.12065 0.2794)
			(stroke
				(width 0.1)
				(type default)
			)
			(layer "F.Fab")
		)
		(fp_line
			(start -0.12065 0.2794)
			(end -0.12065 0.3048)
			(stroke
				(width 0.1)
				(type default)
			)
			(layer "F.Fab")
		)
		(fp_line
			(start 0.67945 0.3048)
			(end 0.120396 0.3048)
			(stroke
				(width 0.1)
				(type default)
			)
			(layer "F.Fab")
		)
		(fp_line
			(start 0.120396 0.3048)
			(end 0.120396 0.2794)
			(stroke
				(width 0.1)
				(type default)
			)
			(layer "F.Fab")
		)
		(fp_line
			(start -0.12065 0.3048)
			(end -0.67945 0.3048)
			(stroke
				(width 0.1)
				(type default)
			)
			(layer "F.Fab")
		)
		(fp_line
			(start -0.67945 0.3048)
			(end -0.67945 -0.305054)
			(stroke
				(width 0.1)
				(type default)
			)
			(layer "F.Fab")
		)
		(pad "1" smd circle
			(at -0.40005 0 90)
			(size 0 0)
			(layers "F.Cu" "F.Mask" "F.Paste")
			(net "P12V_OCP_IMON_1")
		)
		(pad "2" smd circle
			(at 0.40005 0 90)
			(size 0 0)
			(layers "F.Cu" "F.Mask" "F.Paste")
			(net "GND")
		)
	)
)
